(kicad_pcb
	(version 20260206)
	(generator "pcbnew")
	(generator_version "10.0")
	(general
		(thickness 1.6)
		(legacy_teardrops no)
	)
	(paper "A4")
	(title_block
		(title "Bryce Canyon_R.DPB_16317-1_OCP.brd")
		(comment 1 "Bryce Canyon / footprints 424-431 of 2099")
	)
	(layers
		(0 "F.Cu" signal "TOP")
		(4 "In1.Cu" signal "L2GND")
		(6 "In2.Cu" signal "L3")
		(8 "In3.Cu" signal "L4VCC")
		(10 "In4.Cu" signal "L5VCC")
		(12 "In5.Cu" signal "L6")
		(14 "In6.Cu" signal "L7GND")
		(2 "B.Cu" signal "BOTTOM")
		(9 "F.Adhes" user "F.Adhesive")
		(11 "B.Adhes" user "B.Adhesive")
		(13 "F.Paste" user "Package Geometry/Pastemask Top")
		(15 "B.Paste" user "Package Geometry/Pastemask Bottom")
		(5 "F.SilkS" user "Ref Des/Silkscreen Top")
		(7 "B.SilkS" user "Ref Des/Silkscreen Bottom")
		(1 "F.Mask" user "Board Geometry/Soldermask Top")
		(3 "B.Mask" user "Board Geometry/Soldermask Bottom")
		(17 "Dwgs.User" user "User.Drawings")
		(19 "Cmts.User" user "User.Comments")
		(21 "Eco1.User" user "User.Eco1")
		(23 "Eco2.User" user "User.Eco2")
		(25 "Edge.Cuts" user "Board Geometry/Outline")
		(27 "Margin" user)
		(31 "F.CrtYd" user "Package Geometry/Place Bound Top")
		(29 "B.CrtYd" user "Package Geometry/Place Bound Bottom")
		(35 "F.Fab" user "Ref Des/Assembly Top")
		(33 "B.Fab" user "Ref Des/Assembly Bottom")
	)
	(footprint ""
		(layer "F.Cu")
		(at 445.415924 -39.705026)
		(property "Reference" "TP191"
			(at 0 0 0)
			(layer "F.SilkS")
			(hide yes)
			(effects
				(font
					(size 1.27 1.27)
				)
			)
		)
		(property "Value" "*"
			(at -0.0508 -1.6764 0)
			(unlocked yes)
			(layer "F.Fab")
			(hide yes)
			(effects
				(font
					(size 1.016 1.016)
					(thickness 0.1524)
				)
			)
		)
		(property "Device Type" "TPAD32"
			(at -0.0508 -3.2004 0)
			(unlocked yes)
			(layer "F.Fab")
			(hide yes)
			(effects
				(font
					(size 1.016 1.016)
					(thickness 0.1524)
				)
			)
		)
		(duplicate_pad_numbers_are_jumpers no)
		(fp_poly
			(pts
				(arc
					(start 0.4064 0)
					(mid -0.4064 0)
					(end 0.4064 0)
				)
			)
			(stroke
				(width 0)
				(type default)
			)
			(fill no)
			(layer "F.CrtYd")
		)
		(fp_poly
			(pts
				(arc
					(start 0.7112 0)
					(mid -0.7112 0)
					(end 0.7112 0)
				)
			)
			(stroke
				(width 0)
				(type default)
			)
			(fill no)
			(layer "F.Fab")
		)
		(pad "1" smd circle
			(at 0 0)
			(size 0.8128 0.8128)
			(layers "F.Cu" "F.Mask" "F.Paste")
			(net "ACT_HDD_34")
		)
	)
	(footprint ""
		(layer "F.Cu")
		(at 109.474 -254.508 -90)
		(property "Reference" "R217"
			(at 0 0 270)
			(layer "F.SilkS")
			(hide yes)
			(effects
				(font
					(size 1.27 1.27)
				)
			)
		)
		(property "Value" "300KR2F-GP"
			(at 0.064008 -3.993896 270)
			(unlocked yes)
			(layer "F.Fab")
			(hide yes)
			(effects
				(font
					(size 1.016 1.016)
					(thickness 0.1524)
				)
			)
		)
		(property "Device Type" "R402H16"
			(at 0.064008 -5.517896 270)
			(unlocked yes)
			(layer "F.Fab")
			(hide yes)
			(effects
				(font
					(size 1.016 1.016)
					(thickness 0.1524)
				)
			)
		)
		(duplicate_pad_numbers_are_jumpers no)
		(fp_line
			(start -0.508 -0.9398)
			(end -0.508 0.9398)
			(stroke
				(width 0.1524)
				(type default)
			)
			(layer "F.SilkS")
		)
		(fp_line
			(start 0.508 -0.9398)
			(end -0.508 -0.9398)
			(stroke
				(width 0.1524)
				(type default)
			)
			(layer "F.SilkS")
		)
		(fp_rect
			(start -0.508 0.9398)
			(end 0.508 -0.9398)
			(stroke
				(width 0)
				(type default)
			)
			(fill no)
			(layer "F.CrtYd")
		)
		(fp_rect
			(start -0.508 0.9398)
			(end 0.508 -0.9398)
			(stroke
				(width 0)
				(type default)
			)
			(fill no)
			(layer "F.Fab")
		)
		(pad "1" smd custom
			(at 0 -0.4445 270)
			(size 0.1397 0.1397)
			(layers "F.Cu" "F.Mask" "F.Paste")
			(net "SW_HDD_N3")
			(options
				(clearance outline)
				(anchor circle)
			)
			(primitives
				(gr_poly
					(pts
						(arc
							(start -0.1778 -0.2794)
							(mid -0.249642 -0.249642)
							(end -0.2794 -0.1778)
						)
						(arc
							(start -0.2794 0.1778)
							(mid -0.249642 0.249642)
							(end -0.1778 0.2794)
						)
						(arc
							(start 0.1778 0.2794)
							(mid 0.249642 0.249642)
							(end 0.2794 0.1778)
						)
						(arc
							(start 0.2794 -0.1778)
							(mid 0.249642 -0.249642)
							(end 0.1778 -0.2794)
						)
					)
					(width 0)
					(fill yes)
				)
			)
		)
		(pad "2" smd custom
			(at 0 0.4445 270)
			(size 0.1397 0.1397)
			(layers "F.Cu" "F.Mask" "F.Paste")
			(net "P12V_B")
			(options
				(clearance outline)
				(anchor circle)
			)
			(primitives
				(gr_poly
					(pts
						(arc
							(start -0.1778 -0.2794)
							(mid -0.249642 -0.249642)
							(end -0.2794 -0.1778)
						)
						(arc
							(start -0.2794 0.1778)
							(mid -0.249642 0.249642)
							(end -0.1778 0.2794)
						)
						(arc
							(start 0.1778 0.2794)
							(mid 0.249642 0.249642)
							(end 0.2794 0.1778)
						)
						(arc
							(start 0.2794 -0.1778)
							(mid 0.249642 -0.249642)
							(end 0.1778 -0.2794)
						)
					)
					(width 0)
					(fill yes)
				)
			)
		)
	)
	(footprint ""
		(layer "F.Cu")
		(at 32.508952 -18.750026 -90)
		(property "Reference" "VIA50"
			(at 0 0 270)
			(layer "F.SilkS")
			(hide yes)
			(effects
				(font
					(size 1.27 1.27)
				)
			)
		)
		(property "Value" "100OHM-8L-2D36MM-L16-GP"
			(at -3.4036 -0.4572 270)
			(unlocked yes)
			(layer "F.Fab")
			(hide yes)
			(effects
				(font
					(size 1.016 1.016)
					(thickness 0.1524)
				)
			)
		)
		(property "Device Type" "VIA-PCIE-4P-427097"
			(at -3.4036 -1.9812 270)
			(unlocked yes)
			(layer "F.Fab")
			(hide yes)
			(effects
				(font
					(size 1.016 1.016)
					(thickness 0.1524)
				)
			)
		)
		(duplicate_pad_numbers_are_jumpers no)
		(fp_rect
			(start -2.1336 0.4826)
			(end 2.1336 -0.4826)
			(stroke
				(width 0)
				(type default)
			)
			(fill no)
			(layer "F.CrtYd")
		)
		(fp_rect
			(start -2.1336 0.4826)
			(end 2.1336 -0.4826)
			(stroke
				(width 0)
				(type default)
			)
			(fill no)
			(layer "F.Fab")
		)
		(pad "1" thru_hole circle
			(at -1.651 0 270)
			(size 0.508 0.508)
			(drill 0.254)
			(layers "*.Cu" "*.Mask")
			(remove_unused_layers no)
			(net "GND")
			(clearance 0.2286)
			(thermal_gap 0.2286)
		)
		(pad "2" thru_hole circle
			(at -0.635 0 270)
			(size 0.508 0.508)
			(drill 0.254)
			(layers "*.Cu" "*.Mask")
			(remove_unused_layers no)
			(net "PHY_DRV_B_TO_SCC_B_24_DP")
			(clearance 0.2286)
			(thermal_gap 0.2286)
		)
		(pad "3" thru_hole circle
			(at 0.635 0 270)
			(size 0.508 0.508)
			(drill 0.254)
			(layers "*.Cu" "*.Mask")
			(remove_unused_layers no)
			(net "PHY_DRV_B_TO_SCC_B_24_DN")
			(clearance 0.2286)
			(thermal_gap 0.2286)
		)
		(pad "4" thru_hole circle
			(at 1.651 0 270)
			(size 0.508 0.508)
			(drill 0.254)
			(layers "*.Cu" "*.Mask")
			(remove_unused_layers no)
			(net "GND")
			(clearance 0.2286)
			(thermal_gap 0.2286)
		)
	)
	(footprint ""
		(layer "F.Cu")
		(at 35.400996 -375.92)
		(property "Reference" "R930"
			(at 0 0 0)
			(layer "F.SilkS")
			(hide yes)
			(effects
				(font
					(size 1.27 1.27)
				)
			)
		)
		(property "Value" "100KR2F-L1-GP"
			(at 0.064008 -3.993896 0)
			(unlocked yes)
			(layer "F.Fab")
			(hide yes)
			(effects
				(font
					(size 1.016 1.016)
					(thickness 0.1524)
				)
			)
		)
		(property "Device Type" "R402H16"
			(at 0.064008 -5.517896 0)
			(unlocked yes)
			(layer "F.Fab")
			(hide yes)
			(effects
				(font
					(size 1.016 1.016)
					(thickness 0.1524)
				)
			)
		)
		(duplicate_pad_numbers_are_jumpers no)
		(fp_line
			(start -0.508 -0.9398)
			(end -0.508 0.9398)
			(stroke
				(width 0.1524)
				(type default)
			)
			(layer "F.SilkS")
		)
		(fp_line
			(start 0.508 -0.9398)
			(end -0.508 -0.9398)
			(stroke
				(width 0.1524)
				(type default)
			)
			(layer "F.SilkS")
		)
		(fp_rect
			(start -0.508 0.9398)
			(end 0.508 -0.9398)
			(stroke
				(width 0)
				(type default)
			)
			(fill no)
			(layer "F.CrtYd")
		)
		(fp_rect
			(start -0.508 0.9398)
			(end 0.508 -0.9398)
			(stroke
				(width 0)
				(type default)
			)
			(fill no)
			(layer "F.Fab")
		)
		(pad "1" smd custom
			(at 0 -0.4445)
			(size 0.1397 0.1397)
			(layers "F.Cu" "F.Mask" "F.Paste")
			(net "P3V3_IN")
			(options
				(clearance outline)
				(anchor circle)
			)
			(primitives
				(gr_poly
					(pts
						(arc
							(start -0.1778 -0.2794)
							(mid -0.249642 -0.249642)
							(end -0.2794 -0.1778)
						)
						(arc
							(start -0.2794 0.1778)
							(mid -0.249642 0.249642)
							(end -0.1778 0.2794)
						)
						(arc
							(start 0.1778 0.2794)
							(mid 0.249642 0.249642)
							(end 0.2794 0.1778)
						)
						(arc
							(start 0.2794 -0.1778)
							(mid 0.249642 -0.249642)
							(end 0.1778 -0.2794)
						)
					)
					(width 0)
					(fill yes)
				)
			)
		)
		(pad "2" smd custom
			(at 0 0.4445)
			(size 0.1397 0.1397)
			(layers "F.Cu" "F.Mask" "F.Paste")
			(net "FAN_0_INS_N")
			(options
				(clearance outline)
				(anchor circle)
			)
			(primitives
				(gr_poly
					(pts
						(arc
							(start -0.1778 -0.2794)
							(mid -0.249642 -0.249642)
							(end -0.2794 -0.1778)
						)
						(arc
							(start -0.2794 0.1778)
							(mid -0.249642 0.249642)
							(end -0.1778 0.2794)
						)
						(arc
							(start 0.1778 0.2794)
							(mid 0.249642 0.249642)
							(end 0.2794 0.1778)
						)
						(arc
							(start 0.2794 -0.1778)
							(mid 0.249642 -0.249642)
							(end 0.1778 -0.2794)
						)
					)
					(width 0)
					(fill yes)
				)
			)
		)
	)
	(footprint ""
		(layer "F.Cu")
		(at 338.455 -28.829 90)
		(property "Reference" "C429"
			(at 0 0 90)
			(layer "F.SilkS")
			(hide yes)
			(effects
				(font
					(size 1.27 1.27)
				)
			)
		)
		(property "Value" "SCD033U25V2KX-GP"
			(at 1.1811 -2.7051 90)
			(unlocked yes)
			(layer "F.Fab")
			(hide yes)
			(effects
				(font
					(size 1.016 1.016)
					(thickness 0.1524)
				)
			)
		)
		(property "Device Type" "C402H22"
			(at 1.1811 -4.2291 90)
			(unlocked yes)
			(layer "F.Fab")
			(hide yes)
			(effects
				(font
					(size 1.016 1.016)
					(thickness 0.1524)
				)
			)
		)
		(duplicate_pad_numbers_are_jumpers no)
		(fp_rect
			(start -0.4318 0.9525)
			(end 0.4318 -0.9525)
			(stroke
				(width 0)
				(type default)
			)
			(fill no)
			(layer "F.CrtYd")
		)
		(fp_rect
			(start -0.4318 0.9525)
			(end 0.4318 -0.9525)
			(stroke
				(width 0)
				(type default)
			)
			(fill no)
			(layer "F.Fab")
		)
		(pad "1" smd custom
			(at 0 -0.4445 90)
			(size 0.1524 0.1524)
			(layers "F.Cu" "F.Mask" "F.Paste")
			(net "P12V_B")
			(options
				(clearance outline)
				(anchor circle)
			)
			(primitives
				(gr_poly
					(pts
						(arc
							(start 0.3048 -0.2032)
							(mid 0.275042 -0.275042)
							(end 0.2032 -0.3048)
						)
						(arc
							(start -0.2032 -0.3048)
							(mid -0.275042 -0.275042)
							(end -0.3048 -0.2032)
						)
						(arc
							(start -0.3048 0.2032)
							(mid -0.275042 0.275042)
							(end -0.2032 0.3048)
						)
						(arc
							(start 0.2032 0.3048)
							(mid 0.275042 0.275042)
							(end 0.3048 0.2032)
						)
					)
					(width 0)
					(fill yes)
				)
			)
		)
		(pad "2" smd custom
			(at 0 0.4445 90)
			(size 0.1524 0.1524)
			(layers "F.Cu" "F.Mask" "F.Paste")
			(net "SW_HDD_N30")
			(options
				(clearance outline)
				(anchor circle)
			)
			(primitives
				(gr_poly
					(pts
						(arc
							(start 0.3048 -0.2032)
							(mid 0.275042 -0.275042)
							(end 0.2032 -0.3048)
						)
						(arc
							(start -0.2032 -0.3048)
							(mid -0.275042 -0.275042)
							(end -0.3048 -0.2032)
						)
						(arc
							(start -0.3048 0.2032)
							(mid -0.275042 0.275042)
							(end -0.2032 0.3048)
						)
						(arc
							(start 0.2032 0.3048)
							(mid 0.275042 0.275042)
							(end 0.3048 0.2032)
						)
					)
					(width 0)
					(fill yes)
				)
			)
		)
	)
	(footprint ""
		(layer "F.Cu")
		(at 36.035996 -365.379 -90)
		(property "Reference" "R929"
			(at 0 0 270)
			(layer "F.SilkS")
			(hide yes)
			(effects
				(font
					(size 1.27 1.27)
				)
			)
		)
		(property "Value" "27KR3F-GP"
			(at -0.0254 -2.5146 270)
			(unlocked yes)
			(layer "F.Fab")
			(hide yes)
			(effects
				(font
					(size 1.016 1.016)
					(thickness 0.1524)
				)
			)
		)
		(property "Device Type" "R603H22"
			(at -0.0254 -4.0386 270)
			(unlocked yes)
			(layer "F.Fab")
			(hide yes)
			(effects
				(font
					(size 1.016 1.016)
					(thickness 0.1524)
				)
			)
		)
		(duplicate_pad_numbers_are_jumpers no)
		(fp_line
			(start -0.4826 0)
			(end -0.2032 0)
			(stroke
				(width 0.2032)
				(type default)
			)
			(layer "F.SilkS")
		)
		(fp_line
			(start 0.2032 0)
			(end 0.4826 0)
			(stroke
				(width 0.2032)
				(type default)
			)
			(layer "F.SilkS")
		)
		(fp_rect
			(start -0.5842 1.3335)
			(end 0.5842 -1.3335)
			(stroke
				(width 0)
				(type default)
			)
			(fill no)
			(layer "F.CrtYd")
		)
		(fp_rect
			(start -0.5842 1.3335)
			(end 0.5842 -1.3335)
			(stroke
				(width 0)
				(type default)
			)
			(fill no)
			(layer "F.Fab")
		)
		(pad "1" smd custom
			(at 0 -0.762 270)
			(size 0.2159 0.2159)
			(layers "F.Cu" "F.Mask" "F.Paste")
			(net "FAN_0_TACH1")
			(options
				(clearance outline)
				(anchor circle)
			)
			(primitives
				(gr_poly
					(pts
						(arc
							(start -0.3302 -0.4318)
							(mid -0.402042 -0.402042)
							(end -0.4318 -0.3302)
						)
						(arc
							(start -0.4318 0.3302)
							(mid -0.402042 0.402042)
							(end -0.3302 0.4318)
						)
						(arc
							(start 0.3302 0.4318)
							(mid 0.402042 0.402042)
							(end 0.4318 0.3302)
						)
						(arc
							(start 0.4318 -0.3302)
							(mid 0.402042 -0.402042)
							(end 0.3302 -0.4318)
						)
					)
					(width 0)
					(fill yes)
				)
			)
		)
		(pad "2" smd custom
			(at 0 0.762 270)
			(size 0.2159 0.2159)
			(layers "F.Cu" "F.Mask" "F.Paste")
			(net "FANTACH_F0")
			(options
				(clearance outline)
				(anchor circle)
			)
			(primitives
				(gr_poly
					(pts
						(arc
							(start -0.3302 -0.4318)
							(mid -0.402042 -0.402042)
							(end -0.4318 -0.3302)
						)
						(arc
							(start -0.4318 0.3302)
							(mid -0.402042 0.402042)
							(end -0.3302 0.4318)
						)
						(arc
							(start 0.3302 0.4318)
							(mid 0.402042 0.402042)
							(end 0.4318 0.3302)
						)
						(arc
							(start 0.4318 -0.3302)
							(mid 0.402042 -0.402042)
							(end 0.3302 -0.4318)
						)
					)
					(width 0)
					(fill yes)
				)
			)
		)
	)
	(footprint ""
		(layer "F.Cu")
		(at 348.582996 -360.934 90)
		(property "Reference" "C530"
			(at 0 0 90)
			(layer "F.SilkS")
			(hide yes)
			(effects
				(font
					(size 1.27 1.27)
				)
			)
		)
		(property "Value" "SC22U25V0MX-2-GP"
			(at -0.00254 -4.78536 90)
			(unlocked yes)
			(layer "F.Fab")
			(hide yes)
			(effects
				(font
					(size 1.016 1.016)
					(thickness 0.1524)
				)
			)
		)
		(property "Device Type" "C1210H111"
			(at -0.00254 -6.38048 90)
			(unlocked yes)
			(layer "F.Fab")
			(hide yes)
			(effects
				(font
					(size 1.016 1.016)
					(thickness 0.1524)
				)
			)
		)
		(duplicate_pad_numbers_are_jumpers no)
		(fp_line
			(start 1.5748 -2.3368)
			(end -1.5748 -2.3368)
			(stroke
				(width 0.1524)
				(type default)
			)
			(layer "F.SilkS")
		)
		(fp_line
			(start -1.5748 -2.3368)
			(end -1.5748 -0.762)
			(stroke
				(width 0.1524)
				(type default)
			)
			(layer "F.SilkS")
		)
		(fp_line
			(start 1.5748 -0.762)
			(end 1.5748 -2.3368)
			(stroke
				(width 0.1524)
				(type default)
			)
			(layer "F.SilkS")
		)
		(fp_line
			(start -1.5748 0.762)
			(end -1.5748 2.3368)
			(stroke
				(width 0.1524)
				(type default)
			)
			(layer "F.SilkS")
		)
		(fp_line
			(start 1.5748 2.3368)
			(end 1.5748 0.762)
			(stroke
				(width 0.1524)
				(type default)
			)
			(layer "F.SilkS")
		)
		(fp_line
			(start -1.5748 2.3368)
			(end 1.5748 2.3368)
			(stroke
				(width 0.1524)
				(type default)
			)
			(layer "F.SilkS")
		)
		(fp_rect
			(start -1.651 2.413)
			(end 1.651 -2.413)
			(stroke
				(width 0)
				(type default)
			)
			(fill no)
			(layer "F.CrtYd")
		)
		(fp_poly
			(pts
				(xy 1.651 2.413) (xy 1.651 -2.413) (xy -1.651 -2.413) (xy -1.651 2.413)
			)
			(stroke
				(width 0)
				(type default)
			)
			(fill no)
			(layer "F.Fab")
		)
		(pad "1" smd rect
			(at 0 -1.4732 90)
			(size 2.794 1.397)
			(layers "F.Cu" "F.Mask" "F.Paste")
			(net "P12V_FAN2")
		)
		(pad "2" smd rect
			(at 0 1.4732 90)
			(size 2.794 1.397)
			(layers "F.Cu" "F.Mask" "F.Paste")
			(net "GND")
		)
	)
	(footprint ""
		(layer "F.Cu")
		(at 346.700094 -180.399944)
		(property "Reference" "LED8"
			(at 0 0 0)
			(layer "F.SilkS")
			(hide yes)
			(effects
				(font
					(size 1.27 1.27)
				)
			)
		)
		(property "Value" "LED-BY-19-GP"
			(at -2.132076 1.414018 0)
			(unlocked yes)
			(layer "F.Fab")
			(hide yes)
			(effects
				(font
					(size 1.016 1.016)
					(thickness 0.1524)
				)
			)
		)
		(property "Device Type" "LED-1615-4PH26"
			(at -2.132076 -0.109982 0)
			(unlocked yes)
			(layer "F.Fab")
			(hide yes)
			(effects
				(font
					(size 1.016 1.016)
					(thickness 0.1524)
				)
			)
		)
		(duplicate_pad_numbers_are_jumpers no)
		(fp_line
			(start -1.2954 0.254)
			(end -1.2954 1.6002)
			(stroke
				(width 0.508)
				(type default)
			)
			(layer "F.SilkS")
		)
		(fp_line
			(start -1.2954 1.6002)
			(end 1.2954 1.6002)
			(stroke
				(width 0.508)
				(type default)
			)
			(layer "F.SilkS")
		)
		(fp_line
			(start -1.1176 -1.4224)
			(end 1.1176 -1.4224)
			(stroke
				(width 0.1524)
				(type default)
			)
			(layer "F.SilkS")
		)
		(fp_line
			(start -1.1176 1.4224)
			(end -1.1176 -1.4224)
			(stroke
				(width 0.1524)
				(type default)
			)
			(layer "F.SilkS")
		)
		(fp_line
			(start 1.1176 -1.4224)
			(end 1.1176 1.4224)
			(stroke
				(width 0.1524)
				(type default)
			)
			(layer "F.SilkS")
		)
		(fp_line
			(start 1.1176 1.4224)
			(end -1.1176 1.4224)
			(stroke
				(width 0.1524)
				(type default)
			)
			(layer "F.SilkS")
		)
		(fp_line
			(start 1.2954 1.6002)
			(end 1.2954 0.254)
			(stroke
				(width 0.508)
				(type default)
			)
			(layer "F.SilkS")
		)
		(fp_rect
			(start -0.7493 0.8001)
			(end 0.7493 -0.8001)
			(stroke
				(width 0)
				(type default)
			)
			(fill no)
			(layer "F.CrtYd")
		)
		(fp_poly
			(pts
				(xy -1.3716 1.6764) (xy -1.3716 -1.6764) (xy 1.3716 -1.6764) (xy 1.3716 0.0635) (xy 0.7493 0.0635)
				(xy 0.7493 -0.8001) (xy -0.7493 -0.8001) (xy -0.7493 0.8001) (xy 0.7493 0.8001) (xy 0.7493 0.0762)
				(xy 1.3716 0.0762) (xy 1.3716 1.6764)
			)
			(stroke
				(width 0)
				(type default)
			)
			(fill no)
			(layer "F.CrtYd")
		)
		(fp_rect
			(start -1.3716 1.6764)
			(end 1.3716 -1.6764)
			(stroke
				(width 0)
				(type default)
			)
			(fill no)
			(layer "F.Fab")
		)
		(pad "1" smd rect
			(at 0.50038 -0.73025)
			(size 0.7112 0.8636)
			(layers "F.Cu" "F.Mask" "F.Paste")
			(net "DRV_ACT_7")
		)
		(pad "2" smd rect
			(at -0.50038 -0.73025)
			(size 0.7112 0.8636)
			(layers "F.Cu" "F.Mask" "F.Paste")
			(net "FLT_HDD7")
		)
		(pad "3" smd rect
			(at 0.50038 0.73025)
			(size 0.7112 0.8636)
			(layers "F.Cu" "F.Mask" "F.Paste")
			(net "DRV_ACT_7_N")
		)
		(pad "4" smd rect
			(at -0.50038 0.73025)
			(size 0.7112 0.8636)
			(layers "F.Cu" "F.Mask" "F.Paste")
			(net "FLT_HDD7_N")
		)
	)
)
